FILE_TYPE = CONNECTIVITY;
{Allegro Design Entry HDL 17.2-2016 S081 (4005846) 1/11/2022}
"PAGE_NUMBER" = 183;
0"NC";
1"GND\g";
2"GND\g";
3"GND\g";
4"GND\g";
5"GND\g";
6"GND\g";
7"P3V3_STBY\g";
8"P5V_STBY\g";
9"GND\g";
10"GND\g";
11"GND\g";
12"GND\g";
13"PVDD11_S3_P0\g";
14"SW_PVDD11_S3_P0_BOOT2_RC";
15"SW_PVDD11_S3_P0_BOOT1_RC";
16"SW_PVDD11_S3_P0_PH1";
17"SW_PVDD11_S3_P0_SW1";
18"GND\g";
19"P12V_STBY\g";
20"PVDD11_S3_P0\g";
21"GND\g";
22"PVDD11_S3_P0\g";
23"GND\g";
24"GND\g";
25"GND\g";
26"SW_PVDD11_S3_P0_SW2";
27"SW_PVDD11_S3_P0_BOOT1";
28"PVDD11_S3_P0_VOS1";
29"NC_PVDD11_S3_P0_GL2_1";
30"NC_PVDD11_S3_P0_GL1_1";
31"PVDD11_S3_P0_LSET1";
32"NC_PVDD11_S3_P0_DNC1";
33"PVDD11_S3_P0_IMON1";
34"PVDD11_S3_P0_VCC1";
35"PVDD11_S3_P0_VCCS";
36"SW_PVDD11_S3_P0_SW1_RC";
37"GND\g";
38"GND\g";
39"SW_P12V_STBY_PVDD11_S3_P0_FLT\g";
40"SW_PVDD11_S3_P0_SW2_RC";
41"SW_PVDD11_S3_P0_BOOT2";
42"NC_PVDD11_S3_P0_GL1_2";
43"NC_PVDD11_S3_P0_GL2_2";
44"GND\g";
45"PVDD11_S3_P0_TEMP0";
46"PVDD11_S3_P0_PWM1";
47"PVDD11_S3_P0_PVCC\g";
48"PVDD11_S3_P0_IMON2";
49"PVDD11_S3_P0_TEMP0";
50"PVDD11_S3_P0_LSET2";
51"NC_PVDD11_S3_P0_DNC2";
52"PVDD11_S3_P0_PWM2";
53"PVDD11_S3_P0_VCCS";
54"PVDD11_S3_P0_PVCC\g";
55"SW_P12V_STBY_PVDD11_S3_P0_FLT\g";
56"PVDD11_S3_P0\g";
57"SW_PVDD11_S3_P0_PH2";
58"PVDD11_S3_P0_VOS2";
59"PVDD11_S3_P0_VCC2";
%"Q_INDUCTOR"
"1","(-3300,4500)","0","pure_quanta","I101";
;
LOCATION"PL23"
$SEC"1"
CDS_SEC"1"
MATERIAL"IND"
VALUE"90NH/155AA"
PART_NUMBER"CVA90^0KZ04"
PACK_TYPE"SMLF"
CDS_LIB"pure_quanta"
NEEDS_NO_SIZE"TRUE";
"1"
$PN"1"17;
"2"
$PN"2"20;
%"VCC_CORE"
"1","(-3925,5725)","0","pure_quanta_power","I104";
;
HDL_POWER"SW_P12V_STBY_PVDD11_S3_P0_FLT"
CDS_LIB"pure_quanta_power";
"A"55;
%"Q_INDUCTOR"
"1","(-3400,1575)","0","pure_quanta","I105";
;
LOCATION"PL22"
$SEC"1"
CDS_SEC"1"
MATERIAL"IND"
VALUE"90NH/155AA"
PART_NUMBER"CVA90^0KZ04"
PACK_TYPE"SMLF"
NEEDS_NO_SIZE"TRUE"
CDS_LIB"pure_quanta";
"1"
$PN"1"26;
"2"
$PN"2"56;
%"Q_CAP"
"1","(-4075,2450)","0","pure_quanta","I107";
;
LOCATION"PC216_2"
$SEC"1"
CDS_SEC"1"
MATERIAL"X6S"
TOLERANCE"10%"
VALUE"10UF"
PART_NUMBER"CH6104KEA00"
VOLTAGE"25V"
PACK_TYPE"C0805"
CDS_LIB"pure_quanta";
"B"
$PN"2"37;
"A"
$PN"1"39;
%"Q_RES"
"1","(-3800,3500)","0","pure_quanta","I110";
;
LOCATION"PR137"
$SEC"1"
CDS_SEC"1"
WATTAGE"1/16W"
MATERIAL"CHIP"
TOLERANCE"5%"
VALUE"0"
PART_NUMBER"CS00002JB38"
PACK_TYPE"0402LF"
CDS_LIB"pure_quanta";
"B"
$PN"2"20;
"A"
$PN"1"28;
%"Q_RES"
"1","(-3475,600)","0","pure_quanta","I111";
;
LOCATION"PR138"
$SEC"1"
CDS_SEC"1"
WATTAGE"1/16W"
MATERIAL"CHIP"
TOLERANCE"5%"
VALUE"0"
PART_NUMBER"CS00002JB38"
PACK_TYPE"0402LF"
CDS_LIB"pure_quanta";
"B"
$PN"2"56;
"A"
$PN"1"58;
%"Q_CAPP"
"1","(-2425,2900)","0","pure_quanta","I118";
;
LOCATION"PC226"
$SEC"1"
CDS_SEC"1"
MATERIAL"SPCAP"
TOLERANCE"20%"
VALUE"470UF"
PART_NUMBER"CH747LM8825"
VOLTAGE"2.5V"
PACK_TYPE"SMLF"
CDS_LIB"pure_quanta";
"A"
$PN"1"13;
"B"
$PN"2"25;
%"Q_CAPP"
"1","(-1700,2925)","0","pure_quanta","I119";
;
LOCATION"PC228"
$SEC"1"
CDS_SEC"1"
MATERIAL"OSCON"
PART_NUMBER"CC7390JMZ12"
VOLTAGE"2.5V"
PACK_TYPE"SMLF"
TOLERANCE"20%"
VALUE"390UF"
CDS_LIB"pure_quanta";
"A"
$PN"1"22;
"B"
$PN"2"23;
%"Q_CAPP"
"1","(-1375,2925)","0","pure_quanta","I120";
;
LOCATION"PC229"
$SEC"1"
CDS_SEC"1"
MATERIAL"OSCON"
TOLERANCE"20%"
VALUE"390UF"
PART_NUMBER"CC7390JMZ12"
VOLTAGE"2.5V"
PACK_TYPE"SMLF"
CDS_LIB"pure_quanta";
"A"
$PN"1"22;
"B"
$PN"2"23;
%"Q_CAPP"
"1","(-1075,2925)","0","pure_quanta","I121";
;
LOCATION"PC230"
$SEC"1"
CDS_SEC"1"
MATERIAL"OSCON"
TOLERANCE"20%"
VALUE"390UF"
PART_NUMBER"CC7390JMZ12"
VOLTAGE"2.5V"
PACK_TYPE"SMLF"
CDS_LIB"pure_quanta";
"A"
$PN"1"22;
"B"
$PN"2"23;
%"VCC_CORE"
"1","(-1700,3150)","0","pure_quanta_power","I122";
;
HDL_POWER"PVDD11_S3_P0"
CDS_LIB"pure_quanta_power";
"A"22;
%"UNIVERSAL_GND"
"1","(-1700,2600)","0","pure_quanta_power","I123";
;
CDS_LIB"pure_quanta_power"
HDL_POWER"GND";
"A"23;
%"Q_CAP"
"1","(-5075,5375)","0","pure_quanta","I124";
;
LOCATION"PC209_1"
$SEC"1"
CDS_SEC"1"
MATERIAL"X7R"
TOLERANCE"10%"
VALUE"0.1UF"
PART_NUMBER"CH4104K1B00"
VOLTAGE"25V"
PACK_TYPE"0402"
CDS_LIB"pure_quanta";
"B"
$PN"2"18;
"A"
$PN"1"55;
%"Q_CAP"
"1","(-5025,2450)","0","pure_quanta","I125";
;
LOCATION"PC210_2"
$SEC"1"
CDS_SEC"1"
MATERIAL"X7R"
TOLERANCE"10%"
VALUE"0.1UF"
PART_NUMBER"CH4104K1B00"
VOLTAGE"25V"
PACK_TYPE"0402"
CDS_LIB"pure_quanta";
"B"
$PN"2"37;
"A"
$PN"1"39;
%"Q_CAP"
"1","(-7800,4800)","0","pure_quanta","I126";
;
LOCATION"PC203"
$SEC"1"
CDS_SEC"1"
MATERIAL"X6S"
TOLERANCE"10%"
VALUE"2.2UF"
PART_NUMBER"CH5222KEB01"
VOLTAGE"10V"
PACK_TYPE"C0402"
CDS_LIB"pure_quanta";
"B"
$PN"2"1;
"A"
$PN"1"34;
%"UNIVERSAL_GND"
"1","(-7800,4600)","0","pure_quanta_power","I127";
;
CDS_LIB"pure_quanta_power"
HDL_POWER"GND";
"A"1;
%"UNIVERSAL_GND"
"1","(-7450,5100)","0","pure_quanta_power","I128";
;
CDS_LIB"pure_quanta_power"
HDL_POWER"GND";
"A"2;
%"Q_RES"
"2","(-7800,5350)","0","pure_quanta","I129";
;
LOCATION"PR131"
$SEC"1"
CDS_SEC"1"
WATTAGE"1/16W"
MATERIAL"CHIP"
TOLERANCE"1%"
VALUE"2.2"
PART_NUMBER"CS-2202FB00"
PACK_TYPE"0402LF"
CDS_LIB"pure_quanta";
"A"
$PN"1"54;
"B"
$PN"2"34;
%"Q_CAP"
"1","(-7450,5375)","0","pure_quanta","I130";
;
LOCATION"PC205_11P0_1"
$SEC"1"
CDS_SEC"1"
MATERIAL"X6S"
TOLERANCE"10%"
VALUE"2.2UF"
PART_NUMBER"CH5222KEB01"
VOLTAGE"10V"
PACK_TYPE"C0402"
CDS_LIB"pure_quanta";
"B"
$PN"2"2;
"A"
$PN"1"54;
%"Q_CAP"
"1","(-7800,1875)","0","pure_quanta","I132";
;
LOCATION"PC204"
$SEC"1"
CDS_SEC"1"
MATERIAL"X6S"
TOLERANCE"10%"
VALUE"2.2UF"
PART_NUMBER"CH5222KEB01"
VOLTAGE"10V"
PACK_TYPE"C0402"
CDS_LIB"pure_quanta";
"B"
$PN"2"3;
"A"
$PN"1"59;
%"UNIVERSAL_GND"
"1","(-7800,1675)","0","pure_quanta_power","I133";
;
CDS_LIB"pure_quanta_power"
HDL_POWER"GND";
"A"3;
%"UNIVERSAL_GND"
"1","(-7450,2175)","0","pure_quanta_power","I134";
;
CDS_LIB"pure_quanta_power"
HDL_POWER"GND";
"A"4;
%"Q_RES"
"2","(-7800,2425)","0","pure_quanta","I135";
;
LOCATION"PR132"
$SEC"1"
CDS_SEC"1"
WATTAGE"1/16W"
MATERIAL"CHIP"
TOLERANCE"1%"
VALUE"2.2"
PART_NUMBER"CS-2202FB00"
PACK_TYPE"0402LF"
CDS_LIB"pure_quanta";
"A"
$PN"1"47;
"B"
$PN"2"59;
%"Q_CAP"
"1","(-7450,2450)","0","pure_quanta","I136";
;
LOCATION"PC206_11P0_2"
$SEC"1"
CDS_SEC"1"
MATERIAL"X6S"
TOLERANCE"10%"
VALUE"2.2UF"
PART_NUMBER"CH5222KEB01"
VOLTAGE"10V"
PACK_TYPE"C0402"
CDS_LIB"pure_quanta";
"B"
$PN"2"4;
"A"
$PN"1"47;
%"Q_CAP"
"1","(-3750,5375)","0","pure_quanta","I138";
;
LOCATION"PC219_1"
$SEC"1"
CDS_SEC"1"
MATERIAL"X6S"
TOLERANCE"10%"
VALUE"10UF"
PART_NUMBER"CH6104KEA00"
VOLTAGE"25V"
PACK_TYPE"C0805"
CDS_LIB"pure_quanta";
"B"
$PN"2"18;
"A"
$PN"1"55;
%"Q_CAP"
"1","(-3725,2450)","0","pure_quanta","I139";
;
LOCATION"PC218_2"
$SEC"1"
CDS_SEC"1"
PACK_TYPE"C0805"
PART_NUMBER"CH6104KEA00"
MATERIAL"X6S"
TOLERANCE"10%"
VALUE"10UF"
VOLTAGE"25V"
CDS_LIB"pure_quanta";
"B"
$PN"2"37;
"A"
$PN"1"39;
%"UNIVERSAL_GND"
"1","(-4575,650)","0","pure_quanta_power","I140";
;
CDS_LIB"pure_quanta_power"
HDL_POWER"GND";
"A"5;
%"Q_RES"
"2","(-4575,875)","0","pure_quanta","I141";
;
LOCATION"PR389"
$SEC"1"
CDS_SEC"1"
WATTAGE"1/8W"
MATERIAL"EMPTY"
TOLERANCE"1%"
VALUE"1.5"
PART_NUMBER"CS-1504FB00"
PACK_TYPE"0402LF"
CDS_LIB"pure_quanta";
"A"
$PN"1"40;
"B"
$PN"2"5;
%"Q_CAP"
"1","(-4575,1350)","0","pure_quanta","I142";
;
LOCATION"PC168"
$SEC"1"
CDS_SEC"1"
MATERIAL"EMPTY"
TOLERANCE"10%"
VALUE"560PF"
PART_NUMBER"CH1566K1B09"
VOLTAGE"50V"
PACK_TYPE"C0402"
CDS_LIB"pure_quanta";
"B"
$PN"2"40;
"A"
$PN"1"26;
%"UNIVERSAL_GND"
"1","(-4675,3575)","0","pure_quanta_power","I143";
;
CDS_LIB"pure_quanta_power"
HDL_POWER"GND";
"A"6;
%"Q_RES"
"2","(-4675,3800)","0","pure_quanta","I144";
;
LOCATION"PR482"
$SEC"1"
CDS_SEC"1"
WATTAGE"1/8W"
MATERIAL"EMPTY"
TOLERANCE"1%"
VALUE"1.5"
PART_NUMBER"CS-1504FB00"
PACK_TYPE"0402LF"
CDS_LIB"pure_quanta";
"A"
$PN"1"36;
"B"
$PN"2"6;
%"Q_CAP"
"1","(-4675,4275)","0","pure_quanta","I145";
;
LOCATION"PC169"
$SEC"1"
CDS_SEC"1"
MATERIAL"EMPTY"
TOLERANCE"10%"
VALUE"560PF"
PART_NUMBER"CH1566K1B09"
VOLTAGE"50V"
PACK_TYPE"C0402"
CDS_LIB"pure_quanta";
"B"
$PN"2"36;
"A"
$PN"1"17;
%"VCC_CORE"
"1","(-7600,5950)","0","pure_quanta_power","I146";
;
HDL_POWER"PVDD11_S3_P0_PVCC"
CDS_LIB"pure_quanta_power";
"A"54;
%"VCC_CORE"
"1","(-7800,2850)","0","pure_quanta_power","I147";
;
HDL_POWER"PVDD11_S3_P0_PVCC"
CDS_LIB"pure_quanta_power";
"A"47;
%"VCC_CORE"
"1","(-8100,5950)","0","pure_quanta_power","I148";
;
HDL_POWER"P3V3_STBY"
CDS_LIB"pure_quanta_power";
"A"7;
%"Q_RES"
"1","(-8100,5750)","1","pure_quanta","I149";
;
LOCATION"PR413"
$SEC"1"
CDS_SEC"1"
WATTAGE"1/16W"
MATERIAL"EMPTY"
TOLERANCE"5%"
VALUE"0"
PART_NUMBER"CS00002JB38"
PACK_TYPE"0402LF"
CDS_LIB"pure_quanta";
"B"
$PN"2"7;
"A"
$PN"1"54;
%"Q_RES"
"1","(-7225,4175)","0","pure_quanta","I15";
;
LOCATION"PR133"
$SEC"1"
CDS_SEC"1"
WATTAGE"1/16W"
MATERIAL"EMPTY"
TOLERANCE"1%"
VALUE"4.87K"
PART_NUMBER"CS24872FB07"
PACK_TYPE"0402LF"
CDS_LIB"pure_quanta";
"B"
$PN"2"31;
"A"
$PN"1"12;
%"VCC_CORE"
"1","(-8450,5950)","0","pure_quanta_power","I150";
;
HDL_POWER"P5V_STBY"
CDS_LIB"pure_quanta_power";
"A"8;
%"Q_RES"
"1","(-8450,5750)","1","pure_quanta","I151";
;
LOCATION"PR411"
$SEC"1"
CDS_SEC"1"
WATTAGE"1/16W"
MATERIAL"CHIP"
TOLERANCE"5%"
VALUE"0"
PART_NUMBER"CS00002JB38"
PACK_TYPE"0402LF"
CDS_LIB"pure_quanta";
"B"
$PN"2"8;
"A"
$PN"1"54;
%"Q_RES"
"2","(-1225,4275)","0","pure_quanta","I152";
;
LOCATION"PR414"
$SEC"1"
CDS_SEC"1"
WATTAGE"1/16W"
MATERIAL"CHIP"
TOLERANCE"1%"
VALUE"1K"
PART_NUMBER"TMP_QCS21002FB24"
PACK_TYPE"0402LF"
CDS_LIB"pure_quanta";
"A"
$PN"1"20;
"B"
$PN"2"21;
%"Q_CAPP"
"1","(-2100,2900)","0","pure_quanta","I153";
;
LOCATION"PC800"
$SEC"1"
CDS_SEC"1"
MATERIAL"SPCAP"
TOLERANCE"20%"
VALUE"470UF"
PART_NUMBER"CH747LM8825"
VOLTAGE"2.5V"
PACK_TYPE"SMLF"
CDS_LIB"pure_quanta";
"A"
$PN"1"13;
"B"
$PN"2"25;
%"Q_CAPP"
"1","(-725,2925)","0","pure_quanta","I154";
;
LOCATION"PC801"
$SEC"1"
CDS_SEC"1"
MATERIAL"OSCON"
TOLERANCE"20%"
VALUE"390UF"
PART_NUMBER"CC7390JMZ12"
VOLTAGE"2.5V"
PACK_TYPE"SMLF"
CDS_LIB"pure_quanta";
"A"
$PN"1"22;
"B"
$PN"2"23;
%"Q_RES"
"1","(-4775,4825)","0","pure_quanta","I19";
;
LOCATION"PR135"
$SEC"1"
CDS_SEC"1"
PACK_TYPE"0402LF"
TOLERANCE"1%"
MATERIAL"CHIP"
WATTAGE"1/16W"
VALUE"4.7"
PART_NUMBER"CS-4702FB19"
CDS_LIB"pure_quanta";
"B"
$PN"2"15;
"A"
$PN"1"27;
%"UNIVERSAL_GND"
"1","(-5450,3750)","0","pure_quanta_power","I2";
;
CDS_LIB"pure_quanta_power"
HDL_POWER"GND";
"A"38;
%"Q_CAP"
"1","(-5400,5375)","0","pure_quanta","I23";
;
LOCATION"PC207_1"
$SEC"1"
CDS_SEC"1"
MATERIAL"X6S"
TOLERANCE"10%"
VALUE"1UF"
PART_NUMBER"CH5104KEB02"
VOLTAGE"25V"
PACK_TYPE"C0402"
CDS_LIB"pure_quanta";
"B"
$PN"2"18;
"A"
$PN"1"55;
%"Q_CAP"
"1","(-4775,5375)","0","pure_quanta","I24";
;
LOCATION"PC211_1"
$SEC"1"
CDS_SEC"1"
MATERIAL"X6S"
TOLERANCE"10%"
VALUE"10UF"
PART_NUMBER"CH6104KEA00"
VOLTAGE"25V"
PACK_TYPE"C0805"
CDS_LIB"pure_quanta";
"B"
$PN"2"18;
"A"
$PN"1"55;
%"Q_CAP"
"1","(-4400,5375)","0","pure_quanta","I25";
;
LOCATION"PC213_1"
$SEC"1"
CDS_SEC"1"
MATERIAL"X6S"
TOLERANCE"10%"
VALUE"10UF"
PART_NUMBER"CH6104KEA00"
VOLTAGE"25V"
PACK_TYPE"C0805"
CDS_LIB"pure_quanta";
"B"
$PN"2"18;
"A"
$PN"1"55;
%"Q_CAP"
"1","(-4100,5375)","0","pure_quanta","I26";
;
LOCATION"PC215_1"
$SEC"1"
CDS_SEC"1"
MATERIAL"X6S"
TOLERANCE"10%"
VALUE"10UF"
VOLTAGE"25V"
PACK_TYPE"C0805"
PART_NUMBER"CH6104KEA00"
CDS_LIB"pure_quanta";
"B"
$PN"2"18;
"A"
$PN"1"55;
%"Q_CAPP"
"1","(-3350,5375)","0","pure_quanta","I27";
;
LOCATION"PC220"
$SEC"1"
CDS_SEC"1"
MATERIAL"OSCON"
TOLERANCE"20%"
VALUE"220UF"
PART_NUMBER"CC72204MD02"
VOLTAGE"25V"
PACK_TYPE"THLF"
CDS_LIB"pure_quanta";
"A"
$PN"1"55;
"B"
$PN"2"18;
%"Q_CAP"
"1","(-2325,4300)","0","pure_quanta","I29";
;
LOCATION"PC222"
$SEC"1"
CDS_SEC"1"
MATERIAL"X7R"
TOLERANCE"10%"
VALUE"0.1UF"
PART_NUMBER"CH4104K1B00"
VOLTAGE"25V"
PACK_TYPE"0402"
CDS_LIB"pure_quanta";
"B"
$PN"2"21;
"A"
$PN"1"20;
%"UNIVERSAL_GND"
"1","(-3925,5050)","0","pure_quanta_power","I31";
;
CDS_LIB"pure_quanta_power"
HDL_POWER"GND";
"A"18;
%"Q_INDUCTOR"
"1","(-2925,5575)","0","pure_quanta","I34";
;
LOCATION"PL24"
$SEC"1"
CDS_SEC"1"
MATERIAL"IND"
VALUE"100NH/16A"
PART_NUMBER"CV+10G0MZ12"
PACK_TYPE"SMLF"
NEEDS_NO_SIZE"TRUE"
CDS_LIB"pure_quanta";
"1"
$PN"1"55;
"2"
$PN"2"19;
%"VCC_CORE"
"1","(-2525,5750)","0","pure_quanta_power","I35";
;
HDL_POWER"P12V_STBY"
CDS_LIB"pure_quanta_power";
"A"19;
%"Q_CAP"
"1","(-1975,4300)","0","pure_quanta","I37";
;
LOCATION"PC224_1"
$SEC"1"
CDS_SEC"1"
MATERIAL"X6S"
TOLERANCE"20%"
VALUE"22UF"
PART_NUMBER"TMP_QCH622KMEA01"
VOLTAGE"4V"
PACK_TYPE"0805"
CDS_LIB"pure_quanta";
"B"
$PN"2"21;
"A"
$PN"1"20;
%"UNIVERSAL_GND"
"1","(-1225,3975)","0","pure_quanta_power","I38";
;
CDS_LIB"pure_quanta_power"
HDL_POWER"GND";
"A"21;
%"Q_CAP"
"1","(-1550,4300)","0","pure_quanta","I39";
;
LOCATION"PC227_1"
$SEC"1"
CDS_SEC"1"
MATERIAL"X6S"
TOLERANCE"20%"
VALUE"22UF"
VOLTAGE"4V"
PACK_TYPE"0805"
CDS_LIB"pure_quanta"
PART_NUMBER"TMP_QCH622KMEA01";
"B"
$PN"2"21;
"A"
$PN"1"20;
%"Q_CAP"
"1","(-7900,4200)","0","pure_quanta","I4";
;
LOCATION"PC201_1"
$SEC"1"
CDS_SEC"1"
MATERIAL"X7R"
TOLERANCE"10%"
VALUE"0.1UF"
PART_NUMBER"CH4104K1B00"
VOLTAGE"25V"
PACK_TYPE"0402"
CDS_LIB"pure_quanta";
"B"
$PN"2"10;
"A"
$PN"1"35;
%"VCC_CORE"
"1","(-1225,4600)","0","pure_quanta_power","I40";
;
HDL_POWER"PVDD11_S3_P0"
CDS_LIB"pure_quanta_power";
"A"20;
%"Q_CAP"
"1","(-3950,4700)","0","pure_quanta","I43";
;
LOCATION"PC217"
$SEC"1"
CDS_SEC"1"
MATERIAL"X7R"
TOLERANCE"10%"
VALUE"0.22UF"
PART_NUMBER"CH4223K1B00"
VOLTAGE"16V"
PACK_TYPE"0402"
CDS_LIB"pure_quanta";
"B"
$PN"2"16;
"A"
$PN"1"15;
%"ISL99390FRZTR5935"
"1","(-6075,4475)","0","pure_quanta","I44";
;
LOCATION"PU22"
$SEC"1"
CDS_SEC"1"
PART_TYPE"SMLF"
MATERIAL"IC"
VALUE"ISL99390FRZ-TR5935"
PART_NUMBER"AL099390004"
CDS_LMAN_SYM_OUTLINE"-300,700,250,-650"
NEEDS_NO_SIZE"TRUE"
CDS_LIB"pure_quanta";
"PGND2"
$PN"7_9-20_24"38;
"GL2"
$PN"41"29;
"GL1"
$PN"6"30;
"DNC"
$PN"31"32;
"EN"
$PN"35"34;
"PGND3"
$PN"40"38;
"VOS"
$PN"1"28;
"VIN2"
$PN"30"55;
"PGND1"
$PN"5"38;
"SW"
$PN"10_19"17;
"LSET"
$PN"37"31;
"IOUT"
$PN"38"33;
"TOUT_FLT"
$PN"36"45;
"PVCC"
$PN"4"54;
"PHASE"
$PN"32"16;
"VIN1"
$PN"25_29"55;
"BOOT"
$PN"33"27;
"AGND"
$PN"2"38;
"VCC"
$PN"3"34;
"REFIN"
$PN"39"35;
"PWM"
$PN"34"46;
%"UNIVERSAL_GND"
"1","(-5450,825)","0","pure_quanta_power","I46";
;
CDS_LIB"pure_quanta_power"
HDL_POWER"GND";
"A"44;
%"Q_CAP"
"1","(-7850,1275)","0","pure_quanta","I48";
;
LOCATION"PC202_2"
$SEC"1"
CDS_SEC"1"
MATERIAL"X7R"
TOLERANCE"10%"
VALUE"0.1UF"
PART_NUMBER"CH4104K1B00"
VOLTAGE"25V"
PACK_TYPE"0402"
CDS_LIB"pure_quanta";
"B"
$PN"2"9;
"A"
$PN"1"53;
%"UNIVERSAL_GND"
"1","(-7850,1000)","0","pure_quanta_power","I49";
;
CDS_LIB"pure_quanta_power"
HDL_POWER"GND";
"A"9;
%"UNIVERSAL_GND"
"1","(-7900,3925)","0","pure_quanta_power","I5";
;
CDS_LIB"pure_quanta_power"
HDL_POWER"GND";
"A"10;
%"UNIVERSAL_GND"
"1","(-7525,1075)","0","pure_quanta_power","I50";
;
CDS_LIB"pure_quanta_power"
HDL_POWER"GND";
"A"11;
%"Q_RES"
"1","(-7200,1250)","0","pure_quanta","I52";
;
LOCATION"PR134"
$SEC"1"
CDS_SEC"1"
WATTAGE"1/16W"
MATERIAL"EMPTY"
TOLERANCE"1%"
VALUE"4.87K"
PART_NUMBER"CS24872FB07"
PACK_TYPE"0402LF"
CDS_LIB"pure_quanta";
"B"
$PN"2"50;
"A"
$PN"1"11;
%"UNIVERSAL_GND"
"1","(-7550,4000)","0","pure_quanta_power","I6";
;
CDS_LIB"pure_quanta_power"
HDL_POWER"GND";
"A"12;
%"Q_RES"
"1","(-4700,1900)","0","pure_quanta","I63";
;
LOCATION"PR136"
$SEC"1"
CDS_SEC"1"
PACK_TYPE"0402LF"
TOLERANCE"1%"
MATERIAL"CHIP"
WATTAGE"1/16W"
VALUE"4.7"
PART_NUMBER"CS-4702FB19"
CDS_LIB"pure_quanta";
"B"
$PN"2"14;
"A"
$PN"1"41;
%"Q_CAP"
"1","(-3875,1775)","0","pure_quanta","I66";
;
LOCATION"PC218"
$SEC"1"
CDS_SEC"1"
MATERIAL"X7R"
TOLERANCE"10%"
VALUE"0.22UF"
PART_NUMBER"CH4223K1B00"
VOLTAGE"16V"
PACK_TYPE"0402"
CDS_LIB"pure_quanta";
"B"
$PN"2"57;
"A"
$PN"1"14;
%"Q_CAP"
"1","(-5350,2450)","0","pure_quanta","I67";
;
LOCATION"PC208_2"
$SEC"1"
CDS_SEC"1"
MATERIAL"X6S"
TOLERANCE"10%"
VALUE"1UF"
PART_NUMBER"CH5104KEB02"
VOLTAGE"25V"
PACK_TYPE"C0402"
CDS_LIB"pure_quanta";
"B"
$PN"2"37;
"A"
$PN"1"39;
%"Q_CAP"
"1","(-4700,2450)","0","pure_quanta","I69";
;
LOCATION"PC212_2"
$SEC"1"
CDS_SEC"1"
MATERIAL"X6S"
TOLERANCE"10%"
VALUE"10UF"
PART_NUMBER"CH6104KEA00"
VOLTAGE"25V"
PACK_TYPE"C0805"
CDS_LIB"pure_quanta";
"B"
$PN"2"37;
"A"
$PN"1"39;
%"Q_CAP"
"1","(-4400,2450)","0","pure_quanta","I70";
;
LOCATION"PC214_2"
$SEC"1"
CDS_SEC"1"
MATERIAL"X6S"
TOLERANCE"10%"
VALUE"10UF"
VOLTAGE"25V"
PART_NUMBER"CH6104KEA00"
PACK_TYPE"C0805"
CDS_LIB"pure_quanta";
"B"
$PN"2"37;
"A"
$PN"1"39;
%"UNIVERSAL_GND"
"1","(-3725,2125)","0","pure_quanta_power","I71";
;
CDS_LIB"pure_quanta_power"
HDL_POWER"GND";
"A"37;
%"VCC_CORE"
"1","(-3725,2725)","0","pure_quanta_power","I73";
;
HDL_POWER"SW_P12V_STBY_PVDD11_S3_P0_FLT"
CDS_LIB"pure_quanta_power";
"A"39;
%"Q_CAP"
"1","(-2400,1375)","0","pure_quanta","I79";
;
LOCATION"PC221_2"
$SEC"1"
CDS_SEC"1"
MATERIAL"X6S"
TOLERANCE"20%"
VALUE"22UF"
PART_NUMBER"TMP_QCH622KMEA01"
VOLTAGE"4V"
PACK_TYPE"0805"
CDS_LIB"pure_quanta";
"B"
$PN"2"24;
"A"
$PN"1"56;
%"UNIVERSAL_GND"
"1","(-1975,1025)","0","pure_quanta_power","I80";
;
CDS_LIB"pure_quanta_power"
HDL_POWER"GND";
"A"24;
%"Q_CAP"
"1","(-1975,1375)","0","pure_quanta","I81";
;
LOCATION"PC225_2"
$SEC"1"
CDS_SEC"1"
MATERIAL"X6S"
TOLERANCE"20%"
VALUE"22UF"
PART_NUMBER"TMP_QCH622KMEA01"
VOLTAGE"4V"
PACK_TYPE"0805"
CDS_LIB"pure_quanta";
"B"
$PN"2"24;
"A"
$PN"1"56;
%"VCC_CORE"
"1","(-1975,1700)","0","pure_quanta_power","I82";
;
HDL_POWER"PVDD11_S3_P0"
CDS_LIB"pure_quanta_power";
"A"56;
%"ISL99390FRZTR5935"
"1","(-6025,1550)","0","pure_quanta","I84";
;
LOCATION"PU23"
$SEC"1"
CDS_SEC"1"
PART_TYPE"SMLF"
MATERIAL"IC"
VALUE"ISL99390FRZ-TR5935"
PART_NUMBER"AL099390004"
CDS_LMAN_SYM_OUTLINE"-300,700,250,-650"
NEEDS_NO_SIZE"TRUE"
CDS_LIB"pure_quanta";
"PGND2"
$PN"7_9-20_24"44;
"GL2"
$PN"41"43;
"GL1"
$PN"6"42;
"DNC"
$PN"31"51;
"EN"
$PN"35"59;
"PGND3"
$PN"40"44;
"VOS"
$PN"1"58;
"VIN2"
$PN"30"39;
"PGND1"
$PN"5"44;
"SW"
$PN"10_19"26;
"LSET"
$PN"37"50;
"IOUT"
$PN"38"48;
"TOUT_FLT"
$PN"36"49;
"PVCC"
$PN"4"47;
"PHASE"
$PN"32"57;
"VIN1"
$PN"25_29"39;
"BOOT"
$PN"33"41;
"AGND"
$PN"2"44;
"VCC"
$PN"3"59;
"REFIN"
$PN"39"53;
"PWM"
$PN"34"52;
%"UNIVERSAL_GND"
"1","(-2750,2575)","0","pure_quanta_power","I90";
;
CDS_LIB"pure_quanta_power"
HDL_POWER"GND";
"A"25;
%"VCC_CORE"
"1","(-2750,3150)","0","pure_quanta_power","I93";
;
HDL_POWER"PVDD11_S3_P0"
CDS_LIB"pure_quanta_power";
"A"13;
%"Q_CAPP"
"1","(-2750,2900)","0","pure_quanta","I98";
;
LOCATION"PC223"
$SEC"1"
CDS_SEC"1"
MATERIAL"SPCAP"
TOLERANCE"20%"
VALUE"470UF"
PART_NUMBER"CH747LM8825"
VOLTAGE"2.5V"
PACK_TYPE"SMLF"
CDS_LIB"pure_quanta";
"A"
$PN"1"13;
"B"
$PN"2"25;
END.
